(kicad_pcb
	(version 20221018)
	(generator pcbnew)
	(general
    (thickness 1.518)
  )
	(paper "A4")
	(title_block
    (title "Kria K26 Devboard")
    (date "2024-03-26")
    (rev "1.2.5")
    (comment 1 "www.antmicro.com")
    (comment 2 "Antmicro Ltd.")
		(comment 9 "footprints 385-394 of 660")
	)
	(layers
    (0 "F.Cu" mixed)
    (1 "In1.Cu" power)
    (2 "In2.Cu" mixed)
    (3 "In3.Cu" power)
    (4 "In4.Cu" mixed)
    (5 "In5.Cu" power)
    (6 "In6.Cu" mixed)
    (31 "B.Cu" power)
    (32 "B.Adhes" user "B.Adhesive")
    (33 "F.Adhes" user "F.Adhesive")
    (34 "B.Paste" user)
    (35 "F.Paste" user)
    (36 "B.SilkS" user "B.Silkscreen")
    (37 "F.SilkS" user "F.Silkscreen")
    (38 "B.Mask" user)
    (39 "F.Mask" user)
    (40 "Dwgs.User" user "User.Drawings")
    (41 "Cmts.User" user "User.Comments")
    (42 "Eco1.User" user "User.Eco1")
    (43 "Eco2.User" user "User.Eco2")
    (44 "Edge.Cuts" user)
    (45 "Margin" user)
    (46 "B.CrtYd" user "B.Courtyard")
    (47 "F.CrtYd" user "F.Courtyard")
    (48 "B.Fab" user)
    (49 "F.Fab" user)
  )
	(footprint "kria-k26-devboard-footprints:R_0402_1005Metric" (layer "F.Cu")
    (at 87.2744 115.0112 180)
    (descr "Resistor SMD 0402")
    (tags "resistor SMD 0402")
    (property "Author" "Antmicro")
    (property "License" "Apache-2.0")
    (property "MPN" "CR0402-FX-1002GLF")
    (property "Manufacturer" "Bourns")
    (property "Sheetfile" "k26_som.kicad_sch")
    (property "Sheetname" "Xilinx K26 SOM")
    (property "Tolerance" "1%")
    (property "Val" "10k")
    (property "ki_description" "10k resistor in 0402 package with 1% tolerance")
    (attr smd)
    (fp_text reference "R155" (at 1.0744 4.9912 180) (layer "F.SilkS")
        (effects (font (size 0.7 0.7) (thickness 0.15)) (justify left bottom))
    )
    (fp_text value "R_10k_0402" (at 0 1.4 180) (layer "F.Fab") hide
        (effects (font (size 0.7 0.7) (thickness 0.15)) (justify left bottom))
    )
    (fp_text user "${REFERENCE}" (at -0.95 3.168 180) (layer "F.Fab") hide
        (effects (font (size 0.7 0.7) (thickness 0.15)) (justify left bottom))
    )
    (fp_text user "Author: Antmicro" (at -0.95 4.169 180) (layer "F.Fab") hide
        (effects (font (size 0.7 0.7) (thickness 0.15)) (justify left bottom))
    )
    (fp_text user "License: Apache-2.0" (at -0.95 5.169 180) (layer "F.Fab") hide
        (effects (font (size 0.7 0.7) (thickness 0.15)) (justify left bottom))
    )
    (fp_rect (start -0.93 -0.47) (end 0.93 0.47)
      (stroke (width 0.05) (type solid)) (fill none) (layer "F.CrtYd"))
    (fp_rect (start -0.5 -0.25) (end 0.5 0.25)
      (stroke (width 0.15) (type solid)) (fill none) (layer "F.Fab"))
    (pad "1" smd roundrect (at -0.485 0 180) (size 0.59 0.64) (layers "F.Cu" "F.Paste" "F.Mask") (roundrect_rratio 0.25)
      (net 409 "/Xilinx K26 SOM/MIO31_SHUTDOWN") (pintype "passive"))
    (pad "2" smd roundrect (at 0.485 0 180) (size 0.59 0.64) (layers "F.Cu" "F.Paste" "F.Mask") (roundrect_rratio 0.25)
      (net 1 "GND") (pintype "passive"))
  )
	(footprint "kria-k26-devboard-footprints:R_0402_1005Metric" (layer "F.Cu")
    (at 117.16 122.11 -90)
    (descr "Resistor SMD 0402")
    (tags "resistor SMD 0402")
    (property "Author" "Antmicro")
    (property "License" "Apache-2.0")
    (property "MPN" "CR0402-FX-4750GLF")
    (property "Manufacturer" "Bourns")
    (property "Sheetfile" "clock.kicad_sch")
    (property "Sheetname" "Clock distribution")
    (property "Tolerance" "1%")
    (property "Val" "475R")
    (property "ki_description" "475R resistor in 0402 package with 1% tolerance")
    (attr smd)
    (fp_text reference "R22" (at -0.75 -1.52 90) (layer "F.SilkS")
        (effects (font (size 0.7 0.7) (thickness 0.15)) (justify right bottom))
    )
    (fp_text value "R_475R_0402" (at 0 1.4 90) (layer "F.Fab") hide
        (effects (font (size 0.7 0.7) (thickness 0.15)) (justify right bottom))
    )
    (fp_text user "${REFERENCE}" (at -0.95 3.168 90) (layer "F.Fab") hide
        (effects (font (size 0.7 0.7) (thickness 0.15)) (justify right bottom))
    )
    (fp_text user "Author: Antmicro" (at -0.95 4.169 90) (layer "F.Fab") hide
        (effects (font (size 0.7 0.7) (thickness 0.15)) (justify right bottom))
    )
    (fp_text user "License: Apache-2.0" (at -0.95 5.169 90) (layer "F.Fab") hide
        (effects (font (size 0.7 0.7) (thickness 0.15)) (justify right bottom))
    )
    (fp_rect (start -0.93 -0.47) (end 0.93 0.47)
      (stroke (width 0.05) (type solid)) (fill none) (layer "F.CrtYd"))
    (fp_rect (start -0.5 -0.25) (end 0.5 0.25)
      (stroke (width 0.15) (type solid)) (fill none) (layer "F.Fab"))
    (pad "1" smd roundrect (at -0.485 0 270) (size 0.59 0.64) (layers "F.Cu" "F.Paste" "F.Mask") (roundrect_rratio 0.25)
      (net 642 "Net-(U7-I_{REF})") (pintype "passive"))
    (pad "2" smd roundrect (at 0.485 0 270) (size 0.59 0.64) (layers "F.Cu" "F.Paste" "F.Mask") (roundrect_rratio 0.25)
      (net 1 "GND") (pintype "passive"))
  )
	(footprint "kria-k26-devboard-footprints:R_0603_1608Metric" (layer "F.Cu")
    (at 176.2 115.5 180)
    (descr "Resistor SMD 0603")
    (tags "resistor SMD 0603")
    (property "Author" "Antmicro")
    (property "License" "Apache-2.0")
    (property "MPN" "PMR03EZPJ000")
    (property "Manufacturer" "ROHM Semiconductor")
    (property "Max. Curr." "22.4A")
    (property "Sheetfile" "dc-dc-conventers.kicad_sch")
    (property "Sheetname" "DC/DC conventers")
    (property "Val" "0R")
    (property "ki_description" "Metal strip 0Ohm jumper 22.4A")
    (property "ki_keywords" "Metal strip 0Ohm jumper 22.4A high power hpwr current")
    (attr smd)
    (fp_text reference "R164" (at 1.04 0.94 180) (layer "F.SilkS")
        (effects (font (size 0.7 0.7) (thickness 0.15)) (justify left bottom))
    )
    (fp_text value "R_0R_22.4A_0603" (at 0 1.6 180) (layer "F.Fab") hide
        (effects (font (size 0.7 0.7) (thickness 0.15)) (justify left bottom))
    )
    (fp_text user "${REFERENCE}" (at -1.25 3.898 180) (layer "F.Fab") hide
        (effects (font (size 0.7 0.7) (thickness 0.15)) (justify left bottom))
    )
    (fp_text user "Author: Antmicro" (at -1.25 4.9 180) (layer "F.Fab") hide
        (effects (font (size 0.7 0.7) (thickness 0.15)) (justify left bottom))
    )
    (fp_text user "License: Apache-2.0" (at -1.25 5.9 180) (layer "F.Fab") hide
        (effects (font (size 0.7 0.7) (thickness 0.15)) (justify left bottom))
    )
    (fp_line (start -0.3 -0.3) (end 0.3 -0.3)
      (stroke (width 0.15) (type solid)) (layer "F.SilkS"))
    (fp_line (start -0.3 0.3) (end 0.3 0.3)
      (stroke (width 0.15) (type solid)) (layer "F.SilkS"))
    (fp_rect (start -1.25 -0.7) (end 1.25 0.7)
      (stroke (width 0.05) (type solid)) (fill none) (layer "F.CrtYd"))
    (fp_rect (start -0.8 -0.4) (end 0.8 0.4)
      (stroke (width 0.15) (type solid)) (fill none) (layer "F.Fab"))
    (pad "1" smd roundrect (at -0.7 0 180) (size 0.6 0.8) (layers "F.Cu" "F.Paste" "F.Mask") (roundrect_rratio 0.2)
      (net 767 "/Power Supply/DC/DC conventers/PS_1V8_OUT") (pintype "passive"))
    (pad "2" smd roundrect (at 0.7 0 180) (size 0.6 0.8) (layers "F.Cu" "F.Paste" "F.Mask") (roundrect_rratio 0.2)
      (net 17 "PS_1V8") (pintype "passive"))
  )
	(footprint "kria-k26-devboard-footprints:C_0603_1608Metric" (layer "F.Cu")
    (at 79.115 90.9 180)
    (descr "Capacitor SMD 0603")
    (tags "capacitor 0603")
    (property "Author" "Antmicro")
    (property "License" "Apache-2.0")
    (property "MPN" "GRM188R61A106KE69D")
    (property "Manufacturer" "Murata")
    (property "Sheetfile" "camera.kicad_sch")
    (property "Sheetname" "Camera interface")
    (property "Val" "10u")
    (property "Voltage" "")
    (property "ki_description" " ")
    (attr smd)
    (fp_text reference "C247" (at 4.054 -0.375 180) (layer "F.SilkS")
        (effects (font (size 0.7 0.7) (thickness 0.15)) (justify left bottom))
    )
    (fp_text value "C_10u_0603" (at 0 1.6 180) (layer "F.Fab") hide
        (effects (font (size 0.7 0.7) (thickness 0.15)) (justify left bottom))
    )
    (fp_text user "License: Apache-2.0" (at -1.682 5.895 180) (layer "F.Fab") hide
        (effects (font (size 0.7 0.7) (thickness 0.15)) (justify left bottom))
    )
    (fp_text user "${REFERENCE}" (at -1.682 3.895 180) (layer "F.Fab") hide
        (effects (font (size 0.7 0.7) (thickness 0.15)) (justify left bottom))
    )
    (fp_text user "Author: Antmicro" (at -1.682 4.894 180) (layer "F.Fab") hide
        (effects (font (size 0.7 0.7) (thickness 0.15)) (justify left bottom))
    )
    (fp_line (start -0.3 -0.3) (end 0.3 -0.3)
      (stroke (width 0.15) (type solid)) (layer "F.SilkS"))
    (fp_line (start -0.3 0.3) (end 0.3 0.3)
      (stroke (width 0.15) (type solid)) (layer "F.SilkS"))
    (fp_rect (start -1.24 -0.7) (end 1.24 0.7)
      (stroke (width 0.05) (type solid)) (fill none) (layer "F.CrtYd"))
    (fp_rect (start -0.8 -0.4) (end 0.8 0.4)
      (stroke (width 0.15) (type solid)) (fill none) (layer "F.Fab"))
    (pad "1" smd roundrect (at -0.7 0 180) (size 0.6 0.8) (layers "F.Cu" "F.Paste" "F.Mask") (roundrect_rratio 0.2)
      (net 20 "PL_3V3") (pintype "passive"))
    (pad "2" smd roundrect (at 0.7 0 180) (size 0.6 0.8) (layers "F.Cu" "F.Paste" "F.Mask") (roundrect_rratio 0.2)
      (net 1 "GND") (pintype "passive"))
  )
	(footprint "kria-k26-devboard-footprints:TP_SMD_0.75mm" (layer "F.Cu")
    (at 81.55 102.9 180)
    (property "Author" "Antmicro")
    (property "License" "Apache-2.0")
    (property "MPN" "")
    (property "Manufacturer" "")
    (property "Sheetfile" "k26_som.kicad_sch")
    (property "Sheetname" "Xilinx K26 SOM")
    (property "ki_description" "Test Point 0.75mm")
    (attr exclude_from_pos_files)
    (fp_text reference "TP58" (at 3.36 -0.2808 180) (layer "F.SilkS")
        (effects (font (size 0.7 0.7) (thickness 0.15)) (justify left bottom))
    )
    (fp_text value "TP_0.75mm_SMD" (at 0 1.2 180) (layer "F.Fab") hide
        (effects (font (size 0.7 0.7) (thickness 0.15)) (justify left bottom))
    )
    (fp_text user "License: Apache-2.0" (at -0.4 5.101 180) (layer "F.Fab") hide
        (effects (font (size 0.7 0.7) (thickness 0.15)) (justify left bottom))
    )
    (fp_text user "${REFERENCE}" (at -0.4 2.7 180) (layer "F.Fab") hide
        (effects (font (size 0.7 0.7) (thickness 0.15)) (justify left bottom))
    )
    (fp_text user "Author: Antmicro" (at -0.4 3.901 180) (layer "F.Fab") hide
        (effects (font (size 0.7 0.7) (thickness 0.15)) (justify left bottom))
    )
    (pad "1" smd circle (at 0 0 180) (size 0.75 0.75) (layers "F.Cu" "F.Mask")
      (net 476 "/Xilinx K26 SOM/MIO26") (pinfunction "1") (pintype "passive"))
  )
	(footprint "kria-k26-devboard-footprints:SW_KMR211NGLFS_SMD" (layer "F.Cu")
    (at 83.65 150.1)
    (descr "KMR211G")
    (tags "SPST Button Switch")
    (property "Author" "Antmicro")
    (property "License" "Apache-2.0")
    (property "MPN" "KMR211NGLFS")
    (property "Manufacturer" "C&K")
    (property "Sheetfile" "k26_som.kicad_sch")
    (property "Sheetname" "Xilinx K26 SOM")
    (attr smd)
    (fp_text reference "S2" (at -2.75 -2.03) (layer "F.SilkS")
        (effects (font (size 0.7 0.7) (thickness 0.15)) (justify left bottom))
    )
    (fp_text value "SW_SPST_KMR211NGLFS" (at -3 3) (layer "F.Fab") hide
        (effects (font (size 0.7 0.7) (thickness 0.15)) (justify left bottom))
    )
    (fp_text user "License: Apache-2.0" (at -3 6.75) (layer "F.Fab") hide
        (effects (font (size 0.7 0.7) (thickness 0.15)) (justify left bottom))
    )
    (fp_text user "Author: Antmicro" (at -3 5.5) (layer "F.Fab") hide
        (effects (font (size 0.7 0.7) (thickness 0.15)) (justify left bottom))
    )
    (fp_text user "${REFERENCE}" (at -3 4.25) (layer "F.Fab") hide
        (effects (font (size 0.7 0.7) (thickness 0.15)) (justify left bottom))
    )
    (fp_line (start -2.101 -1.601) (end -2.101 -1.48)
      (stroke (width 0.15) (type solid)) (layer "F.SilkS"))
    (fp_line (start -2.101 -1.601) (end 2.1 -1.601)
      (stroke (width 0.15) (type solid)) (layer "F.SilkS"))
    (fp_line (start -2.101 1.58) (end -2.101 1.459)
      (stroke (width 0.15) (type solid)) (layer "F.SilkS"))
    (fp_line (start -2.101 1.6) (end 2.1 1.6)
      (stroke (width 0.15) (type solid)) (layer "F.SilkS"))
    (fp_line (start 2.1 -1.601) (end 2.1 -1.48)
      (stroke (width 0.15) (type solid)) (layer "F.SilkS"))
    (fp_line (start 2.1 1.6) (end 2.1 1.499)
      (stroke (width 0.15) (type solid)) (layer "F.SilkS"))
    (fp_rect (start -2.751 -1.75) (end 2.748 1.749)
      (stroke (width 0.05) (type solid)) (fill none) (layer "F.CrtYd"))
    (fp_line (start -2.101 -1.601) (end -2.101 1.6)
      (stroke (width 0.15) (type solid)) (layer "F.Fab"))
    (fp_line (start -2.101 1.6) (end 2.1 1.6)
      (stroke (width 0.15) (type solid)) (layer "F.Fab"))
    (fp_line (start -0.25 -0.802) (end 0.248 -0.802)
      (stroke (width 0.15) (type solid)) (layer "F.Fab"))
    (fp_line (start 0.248 0.8) (end -0.25 0.8)
      (stroke (width 0.15) (type solid)) (layer "F.Fab"))
    (fp_line (start 2.1 -1.601) (end -2.101 -1.601)
      (stroke (width 0.15) (type solid)) (layer "F.Fab"))
    (fp_line (start 2.1 1.6) (end 2.1 -1.601)
      (stroke (width 0.15) (type solid)) (layer "F.Fab"))
    (fp_arc (start -0.25 0.8) (mid -1.051001 -0.001) (end -0.25 -0.802)
      (stroke (width 0.15) (type solid)) (layer "F.Fab"))
    (fp_arc (start 0.248 -0.802) (mid 1.050001 -0.001) (end 0.248 0.8)
      (stroke (width 0.15) (type solid)) (layer "F.Fab"))
    (pad "1" smd rect (at 2.048 -0.802) (size 0.9 1) (layers "F.Cu" "F.Paste" "F.Mask")
      (net 1 "GND") (pintype "passive"))
    (pad "2" smd rect (at 2.048 0.8) (size 0.9 1) (layers "F.Cu" "F.Paste" "F.Mask")
      (net 467 "/Xilinx K26 SOM/MIO12_FWUEN_C2M_L") (pintype "passive"))
    (pad "3" smd rect (at -2.05 -0.802) (size 0.9 1) (layers "F.Cu" "F.Paste" "F.Mask")
      (net 1 "GND") (pintype "passive"))
    (pad "4" smd rect (at -2.05 0.8) (size 0.9 1) (layers "F.Cu" "F.Paste" "F.Mask")
      (net 467 "/Xilinx K26 SOM/MIO12_FWUEN_C2M_L") (pintype "passive"))
  )
	(footprint "kria-k26-devboard-footprints:Fiducial_1mm_Mask2mm" (layer "F.Cu")
    (at 182.9 149.2)
    (descr "Circular Fiducial, 1mm bare copper, 3mm soldermask opening")
    (tags "fiducial")
    (attr smd board_only exclude_from_bom)
    (fp_text reference "FID2" (at 0 -2.4765) (layer "F.SilkS")
        (effects (font (size 1 1) (thickness 0.15)))
    )
    (fp_text value "Fiducial_1mm_Mask2mm" (at 0 2.6035) (layer "F.Fab") hide
        (effects (font (size 1 1) (thickness 0.15)))
    )
    (fp_text user "${REFERENCE}" (at 0 0) (layer "F.Fab")
        (effects (font (size 0.4 0.4) (thickness 0.06)))
    )
    (fp_text user "License: Apache-2.0" (at -1.25 7.003) (layer "F.Fab") hide
        (effects (font (size 0.7 0.7) (thickness 0.15)) (justify left bottom))
    )
    (fp_text user "Author: Antmicro" (at -1.25 5.803) (layer "F.Fab") hide
        (effects (font (size 0.7 0.7) (thickness 0.15)) (justify left bottom))
    )
    (fp_circle (center 0 0) (end 1.24 0)
      (stroke (width 0.05) (type solid)) (fill none) (layer "F.CrtYd"))
    (fp_circle (center 0 0) (end 0.999 0)
      (stroke (width 0.15) (type solid)) (fill none) (layer "F.Fab"))
    (pad "" smd circle (at 0 0) (size 1 1) (layers "F.Cu" "F.Mask")
      (solder_mask_margin 0.5) (clearance 0.5))
  )
	(footprint "kria-k26-devboard-footprints:Fiducial_1mm_Mask2mm" (layer "F.Cu")
    (at 83.69 144.37)
    (descr "Circular Fiducial, 1mm bare copper, 3mm soldermask opening")
    (tags "fiducial")
    (attr smd board_only exclude_from_bom)
    (fp_text reference "FID1" (at -0.02 -1.9) (layer "F.SilkS")
        (effects (font (size 1 1) (thickness 0.15)))
    )
    (fp_text value "Fiducial_1mm_Mask2mm" (at 0 2.6035) (layer "F.Fab") hide
        (effects (font (size 1 1) (thickness 0.15)))
    )
    (fp_text user "${REFERENCE}" (at 0 0) (layer "F.Fab")
        (effects (font (size 0.4 0.4) (thickness 0.06)))
    )
    (fp_text user "License: Apache-2.0" (at -1.25 7.003) (layer "F.Fab") hide
        (effects (font (size 0.7 0.7) (thickness 0.15)) (justify left bottom))
    )
    (fp_text user "Author: Antmicro" (at -1.25 5.803) (layer "F.Fab") hide
        (effects (font (size 0.7 0.7) (thickness 0.15)) (justify left bottom))
    )
    (fp_circle (center 0 0) (end 1.24 0)
      (stroke (width 0.05) (type solid)) (fill none) (layer "F.CrtYd"))
    (fp_circle (center 0 0) (end 0.999 0)
      (stroke (width 0.15) (type solid)) (fill none) (layer "F.Fab"))
    (pad "" smd circle (at 0 0) (size 1 1) (layers "F.Cu" "F.Mask")
      (solder_mask_margin 0.5) (clearance 0.5))
  )
	(footprint "kria-k26-devboard-footprints:R_0603_1608Metric" (layer "F.Cu")
    (at 166.7 138.8 180)
    (descr "Resistor SMD 0603")
    (tags "resistor SMD 0603")
    (property "Author" "Antmicro")
    (property "License" "Apache-2.0")
    (property "MPN" "PMR03EZPJ000")
    (property "Manufacturer" "ROHM Semiconductor")
    (property "Max. Curr." "22.4A")
    (property "Sheetfile" "dc-dc-conventers.kicad_sch")
    (property "Sheetname" "DC/DC conventers")
    (property "Val" "0R")
    (property "ki_description" "Metal strip 0Ohm jumper 22.4A")
    (property "ki_keywords" "Metal strip 0Ohm jumper 22.4A high power hpwr current")
    (attr smd)
    (fp_text reference "R162" (at 2.12 -1.38 180) (layer "F.SilkS")
        (effects (font (size 0.7 0.7) (thickness 0.15)) (justify left bottom))
    )
    (fp_text value "R_0R_22.4A_0603" (at 0 1.6 180) (layer "F.Fab") hide
        (effects (font (size 0.7 0.7) (thickness 0.15)) (justify left bottom))
    )
    (fp_text user "License: Apache-2.0" (at -1.25 5.9 180) (layer "F.Fab") hide
        (effects (font (size 0.7 0.7) (thickness 0.15)) (justify left bottom))
    )
    (fp_text user "Author: Antmicro" (at -1.25 4.9 180) (layer "F.Fab") hide
        (effects (font (size 0.7 0.7) (thickness 0.15)) (justify left bottom))
    )
    (fp_text user "${REFERENCE}" (at -1.25 3.898 180) (layer "F.Fab") hide
        (effects (font (size 0.7 0.7) (thickness 0.15)) (justify left bottom))
    )
    (fp_line (start -0.3 -0.3) (end 0.3 -0.3)
      (stroke (width 0.15) (type solid)) (layer "F.SilkS"))
    (fp_line (start -0.3 0.3) (end 0.3 0.3)
      (stroke (width 0.15) (type solid)) (layer "F.SilkS"))
    (fp_rect (start -1.25 -0.7) (end 1.25 0.7)
      (stroke (width 0.05) (type solid)) (fill none) (layer "F.CrtYd"))
    (fp_rect (start -0.8 -0.4) (end 0.8 0.4)
      (stroke (width 0.15) (type solid)) (fill none) (layer "F.Fab"))
    (pad "1" smd roundrect (at -0.7 0 180) (size 0.6 0.8) (layers "F.Cu" "F.Paste" "F.Mask") (roundrect_rratio 0.2)
      (net 765 "/Power Supply/DC/DC conventers/PS_3V3_OUT") (pintype "passive"))
    (pad "2" smd roundrect (at 0.7 0 180) (size 0.6 0.8) (layers "F.Cu" "F.Paste" "F.Mask") (roundrect_rratio 0.2)
      (net 15 "PS_3V3") (pintype "passive"))
  )
	(footprint "kria-k26-devboard-footprints:C_0402_1005Metric" (layer "F.Cu")
    (at 79.425 89.6 180)
    (descr "Capacitor SMD 0402")
    (tags "capacitor SMD 0402")
    (property "Author" "Antmicro")
    (property "Dielectric" "X5R")
    (property "License" "Apache-2.0")
    (property "MPN" "GRM155R61H104KE14D")
    (property "Manufacturer" "Murata")
    (property "Sheetfile" "camera.kicad_sch")
    (property "Sheetname" "Camera interface")
    (property "Val" "100n")
    (property "Voltage" "50V")
    (property "ki_description" " ")
    (attr smd)
    (fp_text reference "C244" (at 3.845 -0.37 180) (layer "F.SilkS")
        (effects (font (size 0.7 0.7) (thickness 0.15)) (justify left bottom))
    )
    (fp_text value "C_100n_0402" (at 0 1.4 180) (layer "F.Fab") hide
        (effects (font (size 0.7 0.7) (thickness 0.15)) (justify left bottom))
    )
    (fp_text user "Author: Antmicro" (at -0.932 4.17 180) (layer "F.Fab") hide
        (effects (font (size 0.7 0.7) (thickness 0.15)) (justify left bottom))
    )
    (fp_text user "${REFERENCE}" (at -0.932 3.168 180) (layer "F.Fab") hide
        (effects (font (size 0.7 0.7) (thickness 0.15)) (justify left bottom))
    )
    (fp_text user "License: Apache-2.0" (at -0.932 5.17 180) (layer "F.Fab") hide
        (effects (font (size 0.7 0.7) (thickness 0.15)) (justify left bottom))
    )
    (fp_rect (start -0.94 -0.47) (end 0.94 0.47)
      (stroke (width 0.05) (type solid)) (fill none) (layer "F.CrtYd"))
    (fp_rect (start -0.499 -0.249) (end 0.499 0.249)
      (stroke (width 0.15) (type solid)) (fill none) (layer "F.Fab"))
    (pad "1" smd roundrect (at -0.484 0 180) (size 0.59 0.64) (layers "F.Cu" "F.Paste" "F.Mask") (roundrect_rratio 0.25)
      (net 8 "SOM_5V0") (pintype "passive"))
    (pad "2" smd roundrect (at 0.484 0 180) (size 0.59 0.64) (layers "F.Cu" "F.Paste" "F.Mask") (roundrect_rratio 0.25)
      (net 1 "GND") (pintype "passive"))
  )
)
